(kicad_pcb
	(version 20260206)
	(generator "pcbnew")
	(generator_version "10.0")
	(general
		(thickness 1.6)
		(legacy_teardrops no)
	)
	(paper "A4")
	(title_block
		(title "Wiwynn_Tioga_Pass_MB.brd")
		(comment 1 "Tioga Pass / footprints 3053-3055 of 4770")
	)
	(layers
		(0 "F.Cu" signal "TOP")
		(4 "In1.Cu" signal "L2GND")
		(6 "In2.Cu" signal "L3")
		(8 "In3.Cu" signal "L4GND")
		(10 "In4.Cu" signal "L5")
		(12 "In5.Cu" signal "L6GND")
		(14 "In6.Cu" signal "L7VCC")
		(16 "In7.Cu" signal "L8VCC")
		(18 "In8.Cu" signal "L9GND")
		(20 "In9.Cu" signal "L10")
		(22 "In10.Cu" signal "L11GND")
		(24 "In11.Cu" signal "L12")
		(26 "In12.Cu" signal "L13GND")
		(2 "B.Cu" signal "BOTTOM")
		(9 "F.Adhes" user "F.Adhesive")
		(11 "B.Adhes" user "B.Adhesive")
		(13 "F.Paste" user "Package Geometry/Pastemask Top")
		(15 "B.Paste" user "Package Geometry/Pastemask Bottom")
		(5 "F.SilkS" user "Ref Des/Silkscreen Top")
		(7 "B.SilkS" user "Ref Des/Silkscreen Bottom")
		(1 "F.Mask" user "Board Geometry/Soldermask Top")
		(3 "B.Mask" user "Board Geometry/Soldermask Bottom")
		(17 "Dwgs.User" user "User.Drawings")
		(19 "Cmts.User" user "User.Comments")
		(21 "Eco1.User" user "User.Eco1")
		(23 "Eco2.User" user "User.Eco2")
		(25 "Edge.Cuts" user "Board Geometry/Outline")
		(27 "Margin" user)
		(31 "F.CrtYd" user "Package Geometry/Place Bound Top")
		(29 "B.CrtYd" user "Package Geometry/Place Bound Bottom")
		(35 "F.Fab" user "Ref Des/Assembly Top")
		(33 "B.Fab" user "Ref Des/Assembly Bottom")
	)
	(footprint ""
		(layer "B.Cu")
		(at 459.880208 -150.876254)
		(property "Reference" "U1L1"
			(at 6.400292 -0.849376 0)
			(unlocked yes)
			(layer "B.SilkS")
			(effects
				(font
					(size 0.7874 0.5842)
					(thickness 0.1524)
				)
				(justify left mirror)
			)
		)
		(property "Value" ""
			(at 0 0 0)
			(layer "B.Fab")
			(effects
				(font
					(size 1.27 1.27)
				)
				(justify mirror)
			)
		)
		(duplicate_pad_numbers_are_jumpers no)
		(fp_circle
			(center 1.17856 -2.466086)
			(end 1.30556 -2.466086)
			(stroke
				(width 0.254)
				(type default)
			)
			(fill no)
			(layer "B.SilkS")
		)
		(fp_rect
			(start 0.9144 0.9144)
			(end -0.9144 -0.9144)
			(stroke
				(width 0)
				(type default)
			)
			(fill yes)
			(layer "B.Paste")
		)
		(fp_rect
			(start 1.82499 1.82499)
			(end -1.82499 -1.82499)
			(stroke
				(width 0)
				(type default)
			)
			(fill no)
			(layer "B.CrtYd")
		)
		(fp_line
			(start -1.82499 -1.82499)
			(end -1.82499 1.82499)
			(stroke
				(width 0.1)
				(type default)
			)
			(layer "B.Fab")
		)
		(fp_line
			(start -1.82499 1.82499)
			(end 1.82499 1.82499)
			(stroke
				(width 0.1)
				(type default)
			)
			(layer "B.Fab")
		)
		(fp_line
			(start 1.82499 -1.82499)
			(end -1.82499 -1.82499)
			(stroke
				(width 0.1)
				(type default)
			)
			(layer "B.Fab")
		)
		(fp_line
			(start 1.82499 1.82499)
			(end 1.82499 -1.82499)
			(stroke
				(width 0.1)
				(type default)
			)
			(layer "B.Fab")
		)
		(fp_circle
			(center 1.17856 -2.466086)
			(end 1.30556 -2.466086)
			(stroke
				(width 0.254)
				(type default)
			)
			(fill no)
			(layer "B.Fab")
		)
		(pad "1" smd custom
			(at 0.750062 -1.549908 180)
			(size 0.0762 0.0762)
			(layers "B.Cu" "B.Mask" "B.Paste")
			(net "PWRGD_PVCCIN_CPU0")
			(options
				(clearance outline)
				(anchor circle)
			)
			(primitives
				(gr_poly
					(pts
						(xy 0.1524 0.381)
						(arc
							(start 0.1524 -0.2286)
							(mid 0 -0.381)
							(end -0.1524 -0.2286)
						)
						(xy -0.1524 0.381)
					)
					(width 0)
					(fill yes)
				)
			)
		)
		(pad "2" smd custom
			(at 1.549908 -0.999998 180)
			(size 0.0762 0.0762)
			(layers "B.Cu" "B.Mask" "B.Paste")
			(net "XDP_TRST_N")
			(options
				(clearance outline)
				(anchor circle)
			)
			(primitives
				(gr_poly
					(pts
						(xy -0.381 0.1524)
						(arc
							(start 0.2286 0.1524)
							(mid 0.381 0)
							(end 0.2286 -0.1524)
						)
						(xy -0.381 -0.1524)
					)
					(width 0)
					(fill yes)
				)
			)
		)
		(pad "3" smd custom
			(at 1.549908 -0.500126 180)
			(size 0.0762 0.0762)
			(layers "B.Cu" "B.Mask" "B.Paste")
			(net "XDP_CPU_TRST_N")
			(options
				(clearance outline)
				(anchor circle)
			)
			(primitives
				(gr_poly
					(pts
						(xy -0.381 0.1524)
						(arc
							(start 0.2286 0.1524)
							(mid 0.381 0)
							(end 0.2286 -0.1524)
						)
						(xy -0.381 -0.1524)
					)
					(width 0)
					(fill yes)
				)
			)
		)
		(pad "4" smd custom
			(at 1.549908 0 180)
			(size 0.0762 0.0762)
			(layers "B.Cu" "B.Mask" "B.Paste")
			(net "PWRGD_PVCCIN_CPU0")
			(options
				(clearance outline)
				(anchor circle)
			)
			(primitives
				(gr_poly
					(pts
						(xy -0.381 0.1524)
						(arc
							(start 0.2286 0.1524)
							(mid 0.381 0)
							(end 0.2286 -0.1524)
						)
						(xy -0.381 -0.1524)
					)
					(width 0)
					(fill yes)
				)
			)
		)
		(pad "5" smd custom
			(at 1.549908 0.500126 180)
			(size 0.0762 0.0762)
			(layers "B.Cu" "B.Mask" "B.Paste")
			(net "XDP_TMS")
			(options
				(clearance outline)
				(anchor circle)
			)
			(primitives
				(gr_poly
					(pts
						(xy -0.381 0.1524)
						(arc
							(start 0.2286 0.1524)
							(mid 0.381 0)
							(end 0.2286 -0.1524)
						)
						(xy -0.381 -0.1524)
					)
					(width 0)
					(fill yes)
				)
			)
		)
		(pad "6" smd custom
			(at 1.549908 0.999998 180)
			(size 0.0762 0.0762)
			(layers "B.Cu" "B.Mask" "B.Paste")
			(net "XDP_CPU_TMS")
			(options
				(clearance outline)
				(anchor circle)
			)
			(primitives
				(gr_poly
					(pts
						(xy -0.381 0.1524)
						(arc
							(start 0.2286 0.1524)
							(mid 0.381 0)
							(end 0.2286 -0.1524)
						)
						(xy -0.381 -0.1524)
					)
					(width 0)
					(fill yes)
				)
			)
		)
		(pad "7" smd custom
			(at 0.750062 1.549908 180)
			(size 0.0762 0.0762)
			(layers "B.Cu" "B.Mask" "B.Paste")
			(net "GND")
			(options
				(clearance outline)
				(anchor circle)
			)
			(primitives
				(gr_poly
					(pts
						(xy -0.1524 -0.381)
						(arc
							(start -0.1524 0.2286)
							(mid 0 0.381)
							(end 0.1524 0.2286)
						)
						(xy 0.1524 -0.381)
					)
					(width 0)
					(fill yes)
				)
			)
		)
		(pad "8" smd custom
			(at -0.769874 1.549908 180)
			(size 0.0762 0.0762)
			(layers "B.Cu" "B.Mask" "B.Paste")
			(net "XDP_CPU_TDO")
			(options
				(clearance outline)
				(anchor circle)
			)
			(primitives
				(gr_poly
					(pts
						(xy -0.1524 -0.381)
						(arc
							(start -0.1524 0.2286)
							(mid 0 0.381)
							(end 0.1524 0.2286)
						)
						(xy 0.1524 -0.381)
					)
					(width 0)
					(fill yes)
				)
			)
		)
		(pad "9" smd custom
			(at -1.549908 0.999998 180)
			(size 0.0762 0.0762)
			(layers "B.Cu" "B.Mask" "B.Paste")
			(net "XDP_TDO")
			(options
				(clearance outline)
				(anchor circle)
			)
			(primitives
				(gr_poly
					(pts
						(xy 0.381 -0.1524)
						(arc
							(start -0.2286 -0.1524)
							(mid -0.381 0)
							(end -0.2286 0.1524)
						)
						(xy 0.381 0.1524)
					)
					(width 0)
					(fill yes)
				)
			)
		)
		(pad "10" smd custom
			(at -1.549908 0.500126 180)
			(size 0.0762 0.0762)
			(layers "B.Cu" "B.Mask" "B.Paste")
			(net "PWRGD_PVCCIN_CPU0")
			(options
				(clearance outline)
				(anchor circle)
			)
			(primitives
				(gr_poly
					(pts
						(xy 0.381 -0.1524)
						(arc
							(start -0.2286 -0.1524)
							(mid -0.381 0)
							(end -0.2286 0.1524)
						)
						(xy 0.381 0.1524)
					)
					(width 0)
					(fill yes)
				)
			)
		)
		(pad "11" smd custom
			(at -1.549908 0 180)
			(size 0.0762 0.0762)
			(layers "B.Cu" "B.Mask" "B.Paste")
			(net "XDP_CPU_TDI")
			(options
				(clearance outline)
				(anchor circle)
			)
			(primitives
				(gr_poly
					(pts
						(xy 0.381 -0.1524)
						(arc
							(start -0.2286 -0.1524)
							(mid -0.381 0)
							(end -0.2286 0.1524)
						)
						(xy 0.381 0.1524)
					)
					(width 0)
					(fill yes)
				)
			)
		)
		(pad "12" smd custom
			(at -1.549908 -0.500126 180)
			(size 0.0762 0.0762)
			(layers "B.Cu" "B.Mask" "B.Paste")
			(net "XDP_TDI")
			(options
				(clearance outline)
				(anchor circle)
			)
			(primitives
				(gr_poly
					(pts
						(xy 0.381 -0.1524)
						(arc
							(start -0.2286 -0.1524)
							(mid -0.381 0)
							(end -0.2286 0.1524)
						)
						(xy 0.381 0.1524)
					)
					(width 0)
					(fill yes)
				)
			)
		)
		(pad "13" smd custom
			(at -1.549908 -0.999998 180)
			(size 0.0762 0.0762)
			(layers "B.Cu" "B.Mask" "B.Paste")
			(net "PWRGD_PVCCIN_CPU0")
			(options
				(clearance outline)
				(anchor circle)
			)
			(primitives
				(gr_poly
					(pts
						(xy 0.381 -0.1524)
						(arc
							(start -0.2286 -0.1524)
							(mid -0.381 0)
							(end -0.2286 0.1524)
						)
						(xy 0.381 0.1524)
					)
					(width 0)
					(fill yes)
				)
			)
		)
		(pad "14" smd custom
			(at -0.750062 -1.549908 180)
			(size 0.0762 0.0762)
			(layers "B.Cu" "B.Mask" "B.Paste")
			(net "P3V3_STBY")
			(options
				(clearance outline)
				(anchor circle)
			)
			(primitives
				(gr_poly
					(pts
						(xy 0.1524 0.381)
						(arc
							(start 0.1524 -0.2286)
							(mid 0 -0.381)
							(end -0.1524 -0.2286)
						)
						(xy -0.1524 0.381)
					)
					(width 0)
					(fill yes)
				)
			)
		)
		(pad "15" smd rect
			(at 0 0 180)
			(size 1.8288 1.8288)
			(layers "B.Cu" "B.Mask" "B.Paste")
			(net "GND")
		)
	)
	(footprint ""
		(layer "B.Cu")
		(at 393.581128 -89.622884 -90)
		(property "Reference" "R2W4"
			(at 0.8382 -0.67818 270)
			(unlocked yes)
			(layer "B.SilkS")
			(effects
				(font
					(size 0.4064 0.254)
					(thickness 0.1524)
				)
				(justify left mirror)
			)
		)
		(property "Value" ""
			(at 0 0 90)
			(layer "B.Fab")
			(effects
				(font
					(size 1.27 1.27)
				)
				(justify mirror)
			)
		)
		(duplicate_pad_numbers_are_jumpers no)
		(fp_poly
			(pts
				(xy 0.2794 -0.1016) (xy -0.2794 -0.1016) (xy -0.2794 0.9906) (xy 0.2794 0.9906)
			)
			(stroke
				(width 0)
				(type default)
			)
			(fill no)
			(layer "B.CrtYd")
		)
		(fp_line
			(start -0.2794 0.9906)
			(end -0.2794 -0.1016)
			(stroke
				(width 0.1)
				(type default)
			)
			(layer "B.Fab")
		)
		(fp_line
			(start 0.2794 0.9906)
			(end -0.2794 0.9906)
			(stroke
				(width 0.1)
				(type default)
			)
			(layer "B.Fab")
		)
		(fp_line
			(start -0.2794 -0.1016)
			(end 0.2794 -0.1016)
			(stroke
				(width 0.1)
				(type default)
			)
			(layer "B.Fab")
		)
		(fp_line
			(start 0.2794 -0.1016)
			(end 0.2794 0.9906)
			(stroke
				(width 0.1)
				(type default)
			)
			(layer "B.Fab")
		)
		(pad "1" smd rect
			(at 0 0 90)
			(size 0.508 0.508)
			(layers "B.Cu" "B.Mask" "B.Paste")
			(net "FM_PMBUS_ALERT_BUF_EN_N")
		)
		(pad "2" smd rect
			(at 0 0.889 90)
			(size 0.508 0.508)
			(layers "B.Cu" "B.Mask" "B.Paste")
			(net "FM_PMBUS_ALERT_BUF_EN_R2_N")
		)
		(zone
			(layer "B.Cu")
			(hatch none 0.5)
			(connect_pads
				(clearance 0)
			)
			(min_thickness 0.25)
			(keepout
				(tracks not_allowed)
				(vias allowed)
				(pads allowed)
				(copperpour not_allowed)
				(footprints allowed)
			)
			(placement
				(enabled no)
				(sheetname "")
			)
			(fill
				(thermal_gap 0.5)
				(thermal_bridge_width 0.5)
				(island_removal_mode 0)
			)
			(polygon
				(pts
					(xy 392.946128 -89.368884) (xy 392.946128 -89.876884) (xy 393.327128 -89.876884) (xy 393.327128 -89.368884)
				)
			)
		)
		(zone
			(layer "B.Cu")
			(hatch none 0.5)
			(connect_pads
				(clearance 0)
			)
			(min_thickness 0.25)
			(keepout
				(tracks allowed)
				(vias not_allowed)
				(pads allowed)
				(copperpour not_allowed)
				(footprints allowed)
			)
			(placement
				(enabled no)
				(sheetname "")
			)
			(fill
				(thermal_gap 0.5)
				(thermal_bridge_width 0.5)
				(island_removal_mode 0)
			)
			(polygon
				(pts
					(xy 393.327128 -89.368884) (xy 393.327128 -89.876884) (xy 392.946128 -89.876884) (xy 392.946128 -89.368884)
				)
			)
		)
	)
	(footprint ""
		(layer "B.Cu")
		(at 446.129918 -143.21536 90)
		(property "Reference" "U25W16"
			(at 1.743964 -3.834638 90)
			(unlocked yes)
			(layer "B.SilkS")
			(effects
				(font
					(size 3.048 1.524)
					(thickness 0.000001)
				)
				(justify left mirror)
			)
		)
		(property "Value" ""
			(at 0 0 90)
			(layer "B.Fab")
			(effects
				(font
					(size 1.27 1.27)
				)
				(justify mirror)
			)
		)
		(duplicate_pad_numbers_are_jumpers no)
		(fp_circle
			(center 1.17856 -2.466086)
			(end 1.17856 -2.339086)
			(stroke
				(width 0.254)
				(type default)
			)
			(fill no)
			(layer "B.SilkS")
		)
		(fp_rect
			(start 0.9144 0.9144)
			(end -0.9144 -0.9144)
			(stroke
				(width 0)
				(type default)
			)
			(fill yes)
			(layer "B.Paste")
		)
		(fp_rect
			(start 1.82499 1.82499)
			(end -1.82499 -1.82499)
			(stroke
				(width 0)
				(type default)
			)
			(fill no)
			(layer "B.CrtYd")
		)
		(fp_line
			(start 1.82499 -1.82499)
			(end -1.82499 -1.82499)
			(stroke
				(width 0.1)
				(type default)
			)
			(layer "B.Fab")
		)
		(fp_line
			(start -1.82499 -1.82499)
			(end -1.82499 1.82499)
			(stroke
				(width 0.1)
				(type default)
			)
			(layer "B.Fab")
		)
		(fp_line
			(start 1.82499 1.82499)
			(end 1.82499 -1.82499)
			(stroke
				(width 0.1)
				(type default)
			)
			(layer "B.Fab")
		)
		(fp_line
			(start -1.82499 1.82499)
			(end 1.82499 1.82499)
			(stroke
				(width 0.1)
				(type default)
			)
			(layer "B.Fab")
		)
		(fp_circle
			(center 1.17856 -2.466086)
			(end 1.17856 -2.339086)
			(stroke
				(width 0.254)
				(type default)
			)
			(fill no)
			(layer "B.Fab")
		)
		(pad "1" smd custom
			(at 0.750062 -1.549908 270)
			(size 0.0762 0.0762)
			(layers "B.Cu" "B.Mask" "B.Paste")
			(net "BMC_JTAG_SEL_BUF")
			(options
				(clearance outline)
				(anchor circle)
			)
			(primitives
				(gr_poly
					(pts
						(xy 0.1524 0.381)
						(arc
							(start 0.1524 -0.2286)
							(mid 0 -0.381)
							(end -0.1524 -0.2286)
						)
						(xy -0.1524 0.381)
					)
					(width 0)
					(fill yes)
				)
			)
		)
		(pad "2" smd custom
			(at 1.549908 -0.999998 270)
			(size 0.0762 0.0762)
			(layers "B.Cu" "B.Mask" "B.Paste")
			(net "JTAG_BMC_TDI")
			(options
				(clearance outline)
				(anchor circle)
			)
			(primitives
				(gr_poly
					(pts
						(xy -0.381 0.1524)
						(arc
							(start 0.2286 0.1524)
							(mid 0.381 0)
							(end 0.2286 -0.1524)
						)
						(xy -0.381 -0.1524)
					)
					(width 0)
					(fill yes)
				)
			)
		)
		(pad "3" smd custom
			(at 1.549908 -0.500126 270)
			(size 0.0762 0.0762)
			(layers "B.Cu" "B.Mask" "B.Paste")
			(net "JTAG_BMC_BUF_TDI")
			(options
				(clearance outline)
				(anchor circle)
			)
			(primitives
				(gr_poly
					(pts
						(xy -0.381 0.1524)
						(arc
							(start 0.2286 0.1524)
							(mid 0.381 0)
							(end 0.2286 -0.1524)
						)
						(xy -0.381 -0.1524)
					)
					(width 0)
					(fill yes)
				)
			)
		)
		(pad "4" smd custom
			(at 1.549908 0 270)
			(size 0.0762 0.0762)
			(layers "B.Cu" "B.Mask" "B.Paste")
			(net "BMC_JTAG_SEL_BUF")
			(options
				(clearance outline)
				(anchor circle)
			)
			(primitives
				(gr_poly
					(pts
						(xy -0.381 0.1524)
						(arc
							(start 0.2286 0.1524)
							(mid 0.381 0)
							(end 0.2286 -0.1524)
						)
						(xy -0.381 -0.1524)
					)
					(width 0)
					(fill yes)
				)
			)
		)
		(pad "5" smd custom
			(at 1.549908 0.500126 270)
			(size 0.0762 0.0762)
			(layers "B.Cu" "B.Mask" "B.Paste")
			(net "JTAG_BMC_TMS")
			(options
				(clearance outline)
				(anchor circle)
			)
			(primitives
				(gr_poly
					(pts
						(xy -0.381 0.1524)
						(arc
							(start 0.2286 0.1524)
							(mid 0.381 0)
							(end 0.2286 -0.1524)
						)
						(xy -0.381 -0.1524)
					)
					(width 0)
					(fill yes)
				)
			)
		)
		(pad "6" smd custom
			(at 1.549908 0.999998 270)
			(size 0.0762 0.0762)
			(layers "B.Cu" "B.Mask" "B.Paste")
			(net "JTAG_BMC_BUF_TMS")
			(options
				(clearance outline)
				(anchor circle)
			)
			(primitives
				(gr_poly
					(pts
						(xy -0.381 0.1524)
						(arc
							(start 0.2286 0.1524)
							(mid 0.381 0)
							(end 0.2286 -0.1524)
						)
						(xy -0.381 -0.1524)
					)
					(width 0)
					(fill yes)
				)
			)
		)
		(pad "7" smd custom
			(at 0.750062 1.549908 270)
			(size 0.0762 0.0762)
			(layers "B.Cu" "B.Mask" "B.Paste")
			(net "GND")
			(options
				(clearance outline)
				(anchor circle)
			)
			(primitives
				(gr_poly
					(pts
						(xy -0.1524 -0.381)
						(arc
							(start -0.1524 0.2286)
							(mid 0 0.381)
							(end 0.1524 0.2286)
						)
						(xy 0.1524 -0.381)
					)
					(width 0)
					(fill yes)
				)
			)
		)
		(pad "8" smd custom
			(at -0.769874 1.549908 270)
			(size 0.0762 0.0762)
			(layers "B.Cu" "B.Mask" "B.Paste")
			(net "JTAG_BMC_BUF_TDO")
			(options
				(clearance outline)
				(anchor circle)
			)
			(primitives
				(gr_poly
					(pts
						(xy -0.1524 -0.381)
						(arc
							(start -0.1524 0.2286)
							(mid 0 0.381)
							(end 0.1524 0.2286)
						)
						(xy 0.1524 -0.381)
					)
					(width 0)
					(fill yes)
				)
			)
		)
		(pad "9" smd custom
			(at -1.549908 0.999998 270)
			(size 0.0762 0.0762)
			(layers "B.Cu" "B.Mask" "B.Paste")
			(net "JTAG_BMC_TDO")
			(options
				(clearance outline)
				(anchor circle)
			)
			(primitives
				(gr_poly
					(pts
						(xy 0.381 -0.1524)
						(arc
							(start -0.2286 -0.1524)
							(mid -0.381 0)
							(end -0.2286 0.1524)
						)
						(xy 0.381 0.1524)
					)
					(width 0)
					(fill yes)
				)
			)
		)
		(pad "10" smd custom
			(at -1.549908 0.500126 270)
			(size 0.0762 0.0762)
			(layers "B.Cu" "B.Mask" "B.Paste")
			(net "BMC_JTAG_SEL_BUF")
			(options
				(clearance outline)
				(anchor circle)
			)
			(primitives
				(gr_poly
					(pts
						(xy 0.381 -0.1524)
						(arc
							(start -0.2286 -0.1524)
							(mid -0.381 0)
							(end -0.2286 0.1524)
						)
						(xy 0.381 0.1524)
					)
					(width 0)
					(fill yes)
				)
			)
		)
		(pad "11" smd custom
			(at -1.549908 0 270)
			(size 0.0762 0.0762)
			(layers "B.Cu" "B.Mask" "B.Paste")
			(net "BMC_PWR_DEBUG_BUF_N")
			(options
				(clearance outline)
				(anchor circle)
			)
			(primitives
				(gr_poly
					(pts
						(xy 0.381 -0.1524)
						(arc
							(start -0.2286 -0.1524)
							(mid -0.381 0)
							(end -0.2286 0.1524)
						)
						(xy 0.381 0.1524)
					)
					(width 0)
					(fill yes)
				)
			)
		)
		(pad "12" smd custom
			(at -1.549908 -0.500126 270)
			(size 0.0762 0.0762)
			(layers "B.Cu" "B.Mask" "B.Paste")
			(net "BMC_PWR_DEBUG_N")
			(options
				(clearance outline)
				(anchor circle)
			)
			(primitives
				(gr_poly
					(pts
						(xy 0.381 -0.1524)
						(arc
							(start -0.2286 -0.1524)
							(mid -0.381 0)
							(end -0.2286 0.1524)
						)
						(xy 0.381 0.1524)
					)
					(width 0)
					(fill yes)
				)
			)
		)
		(pad "13" smd custom
			(at -1.549908 -0.999998 270)
			(size 0.0762 0.0762)
			(layers "B.Cu" "B.Mask" "B.Paste")
			(net "BMC_JTAG_SEL_BUF")
			(options
				(clearance outline)
				(anchor circle)
			)
			(primitives
				(gr_poly
					(pts
						(xy 0.381 -0.1524)
						(arc
							(start -0.2286 -0.1524)
							(mid -0.381 0)
							(end -0.2286 0.1524)
						)
						(xy 0.381 0.1524)
					)
					(width 0)
					(fill yes)
				)
			)
		)
		(pad "14" smd custom
			(at -0.750062 -1.549908 270)
			(size 0.0762 0.0762)
			(layers "B.Cu" "B.Mask" "B.Paste")
			(net "P3V3_STBY")
			(options
				(clearance outline)
				(anchor circle)
			)
			(primitives
				(gr_poly
					(pts
						(xy 0.1524 0.381)
						(arc
							(start 0.1524 -0.2286)
							(mid 0 -0.381)
							(end -0.1524 -0.2286)
						)
						(xy -0.1524 0.381)
					)
					(width 0)
					(fill yes)
				)
			)
		)
		(pad "15" smd rect
			(at 0 0 270)
			(size 1.8288 1.8288)
			(layers "B.Cu" "B.Mask" "B.Paste")
			(net "GND")
		)
	)
)
